# T6G (Grand Teton) — schematic netlist excerpt (pin names and nets, part order shuffled) for the footprints in the layout excerpt that follows; sources: Cadence DE-HDL packaged netlist, KiCad conversion of 04192023_DAF0TMB3IC0_F0TG_MB_C_brd_V02_OCP.brd

C616  Q_CAP  0.1UF 10V 10% X7S  pkg C0201  page 290 : A = P0V9_CPU0_RT1_2A ; B = GND
C2293  Q_CAP  22UF 4V 20% X6S  pkg C0402  page 72 : A = PVDD18_S5_P1 ; B = GND
R396  Q_RES  2.2K 5% CHIP  pkg 0402LF  page 27 : A = P3V3_AUX ; B = CPU0_SP5R2

(kicad_pcb
	(version 20260206)
	(generator "pcbnew")
	(generator_version "10.0")
	(general
		(thickness 1.6)
		(legacy_teardrops no)
	)
	(paper "A4")
	(title_block
		(title "04192023_DAF0TMB3IC0_F0TG_MB_C_brd_V02_OCP.brd")
		(comment 1 "Grand Teton / footprints 5683-5685 of 8354")
	)
	(layers
		(0 "F.Cu" signal "TOP")
		(4 "In1.Cu" signal "GND")
		(6 "In2.Cu" signal "IN1")
		(8 "In3.Cu" signal "GND1")
		(10 "In4.Cu" signal "IN2")
		(12 "In5.Cu" signal "GND2")
		(14 "In6.Cu" signal "IN3")
		(16 "In7.Cu" signal "GND3")
		(18 "In8.Cu" signal "VCC")
		(20 "In9.Cu" signal "VCC1")
		(22 "In10.Cu" signal "GND4")
		(24 "In11.Cu" signal "IN4")
		(26 "In12.Cu" signal "GND5")
		(28 "In13.Cu" signal "IN5")
		(30 "In14.Cu" signal "GND6")
		(32 "In15.Cu" signal "IN6")
		(34 "In16.Cu" signal "GND7")
		(2 "B.Cu" signal "BOTTOM")
		(9 "F.Adhes" user "F.Adhesive")
		(11 "B.Adhes" user "B.Adhesive")
		(13 "F.Paste" user "Package Geometry/Pastemask Top")
		(15 "B.Paste" user "Package Geometry/Pastemask Bottom")
		(5 "F.SilkS" user "Ref Des/Silkscreen Top")
		(7 "B.SilkS" user "Ref Des/Silkscreen Bottom")
		(1 "F.Mask" user "Board Geometry/Soldermask Top")
		(3 "B.Mask" user "Board Geometry/Soldermask Bottom")
		(17 "Dwgs.User" user "User.Drawings")
		(19 "Cmts.User" user "User.Comments")
		(21 "Eco1.User" user "User.Eco1")
		(23 "Eco2.User" user "User.Eco2")
		(25 "Edge.Cuts" user "Board Geometry/Outline")
		(27 "Margin" user)
		(31 "F.CrtYd" user "Package Geometry/Place Bound Top")
		(29 "B.CrtYd" user "Package Geometry/Place Bound Bottom")
		(35 "F.Fab" user "Ref Des/Assembly Top")
		(33 "B.Fab" user "Ref Des/Assembly Bottom")
	)
	(footprint ""
		(layer "B.Cu")
		(at 99.100386 -255.845564 180)
		(property "Reference" "C2293"
			(at 0 0 0)
			(layer "B.SilkS")
			(hide yes)
			(effects
				(font
					(size 1.27 1.27)
				)
				(justify mirror)
			)
		)
		(property "Value" ""
			(at 0 0 0)
			(layer "B.Fab")
			(effects
				(font
					(size 1.27 1.27)
				)
				(justify mirror)
			)
		)
		(duplicate_pad_numbers_are_jumpers no)
		(fp_line
			(start 0.7874 0.4064)
			(end 0.7874 -0.4064)
			(stroke
				(width 0.1524)
				(type default)
			)
			(layer "B.SilkS")
		)
		(fp_line
			(start 0.7874 -0.4064)
			(end -0.7874 -0.4064)
			(stroke
				(width 0.1524)
				(type default)
			)
			(layer "B.SilkS")
		)
		(fp_line
			(start -0.7874 0.4064)
			(end 0.7874 0.4064)
			(stroke
				(width 0.1524)
				(type default)
			)
			(layer "B.SilkS")
		)
		(fp_line
			(start -0.7874 -0.4064)
			(end -0.7874 0.4064)
			(stroke
				(width 0.1524)
				(type default)
			)
			(layer "B.SilkS")
		)
		(fp_line
			(start 0.67945 0.3048)
			(end 0.67945 -0.305054)
			(stroke
				(width 0.1)
				(type default)
			)
			(layer "B.Fab")
		)
		(fp_line
			(start 0.67945 -0.305054)
			(end 0.12065 -0.305054)
			(stroke
				(width 0.1)
				(type default)
			)
			(layer "B.Fab")
		)
		(fp_line
			(start 0.12065 0.3048)
			(end 0.67945 0.3048)
			(stroke
				(width 0.1)
				(type default)
			)
			(layer "B.Fab")
		)
		(fp_line
			(start 0.12065 0.2794)
			(end 0.12065 0.3048)
			(stroke
				(width 0.1)
				(type default)
			)
			(layer "B.Fab")
		)
		(fp_line
			(start 0.12065 -0.2794)
			(end -0.12065 -0.2794)
			(stroke
				(width 0.1)
				(type default)
			)
			(layer "B.Fab")
		)
		(fp_line
			(start 0.12065 -0.305054)
			(end 0.12065 -0.2794)
			(stroke
				(width 0.1)
				(type default)
			)
			(layer "B.Fab")
		)
		(fp_line
			(start -0.120396 0.3048)
			(end -0.120396 0.2794)
			(stroke
				(width 0.1)
				(type default)
			)
			(layer "B.Fab")
		)
		(fp_line
			(start -0.120396 0.2794)
			(end 0.12065 0.2794)
			(stroke
				(width 0.1)
				(type default)
			)
			(layer "B.Fab")
		)
		(fp_line
			(start -0.12065 -0.2794)
			(end -0.12065 -0.3048)
			(stroke
				(width 0.1)
				(type default)
			)
			(layer "B.Fab")
		)
		(fp_line
			(start -0.12065 -0.3048)
			(end -0.67945 -0.3048)
			(stroke
				(width 0.1)
				(type default)
			)
			(layer "B.Fab")
		)
		(fp_line
			(start -0.67945 0.3048)
			(end -0.120396 0.3048)
			(stroke
				(width 0.1)
				(type default)
			)
			(layer "B.Fab")
		)
		(fp_line
			(start -0.67945 -0.3048)
			(end -0.67945 0.3048)
			(stroke
				(width 0.1)
				(type default)
			)
			(layer "B.Fab")
		)
		(pad "1" smd circle
			(at 0.40005 0)
			(size 0 0)
			(layers "B.Cu" "B.Mask" "B.Paste")
			(net "PVDD18_S5_P1")
		)
		(pad "2" smd circle
			(at -0.40005 0)
			(size 0 0)
			(layers "B.Cu" "B.Mask" "B.Paste")
			(net "GND")
		)
	)
	(footprint ""
		(layer "B.Cu")
		(at 333.627476 -396.991078 90)
		(property "Reference" "C616"
			(at 0 0 90)
			(layer "B.SilkS")
			(hide yes)
			(effects
				(font
					(size 1.27 1.27)
				)
				(justify mirror)
			)
		)
		(property "Value" ""
			(at 0 0 90)
			(layer "B.Fab")
			(effects
				(font
					(size 1.27 1.27)
				)
				(justify mirror)
			)
		)
		(duplicate_pad_numbers_are_jumpers no)
		(fp_line
			(start 0.299974 -0.150114)
			(end -0.299974 -0.150114)
			(stroke
				(width 0.1)
				(type default)
			)
			(layer "B.Fab")
		)
		(fp_line
			(start -0.299974 -0.150114)
			(end -0.299974 0.150114)
			(stroke
				(width 0.1)
				(type default)
			)
			(layer "B.Fab")
		)
		(fp_line
			(start 0.299974 0.150114)
			(end 0.299974 -0.150114)
			(stroke
				(width 0.1)
				(type default)
			)
			(layer "B.Fab")
		)
		(fp_line
			(start -0.299974 0.150114)
			(end 0.299974 0.150114)
			(stroke
				(width 0.1)
				(type default)
			)
			(layer "B.Fab")
		)
		(pad "1" smd rect
			(at 0.2667 0 270)
			(size 0.3048 0.381)
			(layers "B.Cu" "B.Mask" "B.Paste")
			(net "P0V9_CPU0_RT1_2A")
		)
		(pad "2" smd rect
			(at -0.2667 0 270)
			(size 0.3048 0.381)
			(layers "B.Cu" "B.Mask" "B.Paste")
			(net "GND")
		)
	)
	(footprint ""
		(layer "B.Cu")
		(at 323.386958 -203.917296 -90)
		(property "Reference" "R396"
			(at 0 0 90)
			(layer "B.SilkS")
			(hide yes)
			(effects
				(font
					(size 1.27 1.27)
				)
				(justify mirror)
			)
		)
		(property "Value" ""
			(at 0 0 90)
			(layer "B.Fab")
			(effects
				(font
					(size 1.27 1.27)
				)
				(justify mirror)
			)
		)
		(duplicate_pad_numbers_are_jumpers no)
		(fp_line
			(start -0.7874 0.4064)
			(end 0.7874 0.4064)
			(stroke
				(width 0.1524)
				(type default)
			)
			(layer "B.SilkS")
		)
		(fp_line
			(start 0.7874 0.4064)
			(end 0.7874 -0.4064)
			(stroke
				(width 0.1524)
				(type default)
			)
			(layer "B.SilkS")
		)
		(fp_line
			(start -0.7874 -0.4064)
			(end -0.7874 0.4064)
			(stroke
				(width 0.1524)
				(type default)
			)
			(layer "B.SilkS")
		)
		(fp_line
			(start 0.7874 -0.4064)
			(end -0.7874 -0.4064)
			(stroke
				(width 0.1524)
				(type default)
			)
			(layer "B.SilkS")
		)
		(fp_line
			(start -0.67945 0.3048)
			(end -0.120396 0.3048)
			(stroke
				(width 0.1)
				(type default)
			)
			(layer "B.Fab")
		)
		(fp_line
			(start -0.120396 0.3048)
			(end -0.120396 0.2794)
			(stroke
				(width 0.1)
				(type default)
			)
			(layer "B.Fab")
		)
		(fp_line
			(start 0.12065 0.3048)
			(end 0.67945 0.3048)
			(stroke
				(width 0.1)
				(type default)
			)
			(layer "B.Fab")
		)
		(fp_line
			(start 0.67945 0.3048)
			(end 0.67945 -0.305054)
			(stroke
				(width 0.1)
				(type default)
			)
			(layer "B.Fab")
		)
		(fp_line
			(start -0.120396 0.2794)
			(end 0.12065 0.2794)
			(stroke
				(width 0.1)
				(type default)
			)
			(layer "B.Fab")
		)
		(fp_line
			(start 0.12065 0.2794)
			(end 0.12065 0.3048)
			(stroke
				(width 0.1)
				(type default)
			)
			(layer "B.Fab")
		)
		(fp_line
			(start -0.12065 -0.2794)
			(end -0.12065 -0.3048)
			(stroke
				(width 0.1)
				(type default)
			)
			(layer "B.Fab")
		)
		(fp_line
			(start 0.12065 -0.2794)
			(end -0.12065 -0.2794)
			(stroke
				(width 0.1)
				(type default)
			)
			(layer "B.Fab")
		)
		(fp_line
			(start -0.67945 -0.3048)
			(end -0.67945 0.3048)
			(stroke
				(width 0.1)
				(type default)
			)
			(layer "B.Fab")
		)
		(fp_line
			(start -0.12065 -0.3048)
			(end -0.67945 -0.3048)
			(stroke
				(width 0.1)
				(type default)
			)
			(layer "B.Fab")
		)
		(fp_line
			(start 0.12065 -0.305054)
			(end 0.12065 -0.2794)
			(stroke
				(width 0.1)
				(type default)
			)
			(layer "B.Fab")
		)
		(fp_line
			(start 0.67945 -0.305054)
			(end 0.12065 -0.305054)
			(stroke
				(width 0.1)
				(type default)
			)
			(layer "B.Fab")
		)
		(pad "1" smd circle
			(at 0.40005 0 90)
			(size 0 0)
			(layers "B.Cu" "B.Mask" "B.Paste")
			(net "P3V3_AUX")
		)
		(pad "2" smd circle
			(at -0.40005 0 90)
			(size 0 0)
			(layers "B.Cu" "B.Mask" "B.Paste")
			(net "CPU0_SP5R2")
		)
	)
)
